M48
;Layer_Color=9474304
;FILE_FORMAT=2:5
INCH,LZ
;TYPE=PLATED
T1F00S00C0.00590
T2F00S00C0.00787
T3F00S00C0.00800
T4F00S00C0.01600
T5F00S00C0.02166
T6F00S00C0.02800
T7F00S00C0.02992
T8F00S00C0.03543
T9F00S00C0.05000
T10F00S00C0.05906
T11F00S00C0.06693
T12F00S00C0.07087
T13F00S00C0.11811
T14F00S00C0.12200
T15F00S00C0.12520
;TYPE=NON_PLATED
T16F00S00C0.06598
T17F00S00C0.11811
T18F00S00C0.12520
%
T01
X0564896Y-0236697
T02
X0099016Y-0130315
Y-0125984
Y-0121653
X0103347
X0107677
Y-0125984
X0103347
Y-0130315
X0107677
T03
X0634252Y-0314567
X063975Y-0314581
X065315Y-0314567
X0658647Y-0314581
X0671654Y-0301969
X0673622
X0675591
Y-0298819
X0673622
X0671654
X0615748Y-0305512
X0588976Y-0302756
X0579528Y-030315
X0562598Y-0306693
X0509011Y-0330177
X0508997Y-0335675
X0509405Y-0345138
X0509391Y-0350636
X046063Y-0324852
X045748
X0453937
X0451181
X0447244
X0444488
X0440551
X0437795
X0433858
X0431102
X0431928Y-0311189
X0433465Y-0306742
X0436221
X043937
X0442126
X0445276
X0448032
X0451181
X0453937
X0461811Y-0310679
X0461417Y-029375
X0456299
X045
X0444095
X0437795Y-029375
X0432283Y-029375
X0422441Y-0293789
X0412205Y-029375
X0402362Y-029375
X0402756Y-0311072
X0412598
X0422835
X0273425Y-0374655
X0269502Y-0374291
X025689Y-0374655
X0253655Y-0374421
X0241929Y-0374655
X0237992
X0222638
X0218445Y-0374108
X0210433Y-0374655
X0206496
X0190354Y-0377411
X0178543
X0179134Y-0386466
Y-0389616
X0182677
Y-0386466
X0186614
Y-0389616
X0174941Y-03906
X0163071Y-039073
X0158661Y-0389616
X0156693
X0154724
Y-0386466
X0156693
X0158661
X015748Y-0361811
X0155512
Y-0358661
X015748
X0202441Y-03906
X0212795Y-0387253
X0215945
X0216162Y-0390947
X0226063Y-0390722
X0229331Y-0387253
X023248
X0235144Y-0390416
X0246339Y-0386975
X024941Y-0387253
X0251456Y-0390009
X0259285Y-0390247
X0262006Y-0387255
X0265158Y-0387253
X0267204Y-0390009
X0281201
X0153543Y-0361811
Y-0358661
X0087598Y-033563
Y-0329724
X008563Y-0320313
X0085416Y-0317699
X008563Y-0313976
X0056441Y-03116
X0052441
X0054441Y-03076
X0056441Y-03036
X0052441
X0048441
X0050441Y-02996
X0054441
Y-02916
X0050441
X0046441
Y-02996
X0042441
X0034441
Y-03076
X0026441
X0022441
X0018441
X0014441
X0016441Y-03036
X0020441
X0024441
X0026441Y-02996
X0022441
X0018441
X0014441
X0010441
X0012441Y-03036
Y-03116
X0016441
X0020441
X0024441
X0022441Y-03236
X0018441
X0014441
X0010441
X0012441Y-03276
X0016441
X0014441Y-03316
X0010441
X0020441Y-03356
X0024441
X0028441
X0032441
X0036441
X0040441
X0044441
X0048441
X0052441
X0056441
X0054441Y-03316
X0050441
X0046441
X0042441
X0038441
X0034441
X0030441
X0026441
X0028441Y-03276
X0032441
X0036441
X0034441Y-03236
X0044291Y-0326772
X0052441Y-03276
X0056441
X0054441Y-03236
X0062992Y-0329724
X0067913Y-0340551
X0074803Y-0339567
X007874Y-0340551
X0054441Y-03396
X0050441
X0046441
X0042441
X0038441
X0034441
X0030441
X0026441
X0022441
X0018441
X0020441Y-03436
X0024441
X0028441
X0032441
X0036441
X0040441
X0044441
X0048441
X0052441
X0056441
Y-03516
X0052441
X0048441
X0044441
X0040441
X0036441
X0032441
X0028441
X0024441
X0020441
X0016441
X0012441
X0008441
X0004441
X0000441
X0012441Y-03436
X0016441
X0018441Y-02916
X0022441
X0026575Y-0291339
X0014441Y-02916
X0044291Y-0307087
X-0007559Y-03036
X-0005559Y-02996
X-0009559
X-0025559
X-0023622Y-0294291
X-0025559Y-03156
X-0021559
X-0023622Y-033563
Y-0339567
Y-034252
Y-0346457
X-0023559Y-03516
X-0019559
X-0015559
X-0011559
X-0007559
X-0003559
X-0009559Y-03316
X-0007559Y-03276
Y-02796
X-0011559
X-0009559Y-02756
X-0023622Y-028248
Y-0286417
Y-0290354
X-0025559Y-02676
X-0023559Y-02636
X-0019559
X-0025559Y-02596
X-0023622Y-0241142
Y-0237205
Y-0233268
Y-0229331
X-0009559Y-02276
X-0005559
X-0007559Y-02236
X-0005559Y-02436
X-0009559
X-0013559
X-0011559Y-02476
X-0007559
X-0009559Y-02516
X-0021559Y-02116
X-0025559
X-0023559Y-01916
X-0023622Y-0187992
Y-0184055
Y-0181102
Y-0177165
X-0023559Y-01596
X-0025559Y-01556
Y-01396
X-0013559
X-0009559
X-0005559
X-0007559Y-01436
Y-01676
X-0009559Y-01716
X-0007559Y-01916
X-0003559
X-0011559
X-0015559
X-0009559Y-01956
X-0007559Y-01996
X0012441
X0016441
X0020441
X0022441Y-01956
X0026441
X0024441Y-01916
X0020441
X0016441
X0012441
X0008441
X0004441
X0010441Y-01956
X0014441
X0018441
Y-02036
X0014441
X0010441
X0012441Y-02156
X0016441
X0018441Y-02196
X0014441
X0016441Y-02236
X0012441
X0010441Y-02276
X0020441Y-02316
X0022441Y-02356
X0018441
Y-02436
X0022441
X0020441Y-02476
X0016441
X0012441
X0008441
X0010441Y-02436
X0014441
Y-02516
X0018441
X0022441
X0020441Y-02556
X0016441
X0012441
X0014441Y-02596
X0018441
X0022441
Y-02676
X0018441
X0014441
X0010441
X0012441Y-02716
X0016441
X0020441
X0018441Y-02756
X0014441
X0010441
X0012441Y-02796
X0016441
X0008441
X0022441Y-02836
X0026575Y-0283465
X0024441Y-02876
X0020441
X0044441
X0048441
X0052441
X0056441
Y-02796
X0052441
X0048441
X0044441
X0044291Y-0272638
X0050441Y-02756
X0054441
X0056441Y-02716
X0052441
X0054441Y-02676
X0056441Y-02556
X0052441
X0054441Y-02516
X0050441
X0052441Y-02476
X0056441
X0054441Y-02436
X0050441
X0046441
X0042441
X0038441
X0034441
X0036441Y-02476
X0040441
X0044441
X0048441
X0044291Y-0252953
X0038441Y-02516
X0034441
X0036441Y-02556
X0034441Y-02676
Y-02756
X0063976Y-027559
X0068898Y-0285433
X0075787
X008188Y-0287582
X0087598Y-0281496
Y-027559
X008563Y-0266179
Y-0263779
X0086614Y-0258858
X0106299Y-0263632
X0121063
X007874Y-0238041
X0075787Y-0232283
X0082677
X0086614Y-0227362
Y-0221457
X008563Y-0213583
X0086562Y-0211183
X0081693Y-0205709
X0080709Y-0180118
X0074803Y-0179134
X0068573Y-0179321
X0063976Y-0179134
X0056441Y-01916
X0052441
X0054441Y-01956
X0050441
X0052441Y-01996
X0056441
X0054441Y-02036
X0048441Y-01996
X0044291Y-0200787
Y-0220472
X0040441Y-02236
X0036441
X0038441Y-02276
X0042441
X0046441
X0050441
X0054441
X0056441Y-02236
X0052441
X0048441
Y-02316
X0052441
X0056441
X0054441Y-02356
X0050441
X0046441
X0042441
X0038441
X0034441
X0036441Y-02316
X0040441
X0044441
X0034441Y-02276
Y-02196
X0036441Y-02156
X0052441
X0056441
X0054441Y-02196
X0063976Y-0221457
Y-0227362
X0097125Y-0219488
X009941Y-0216535
X0101378Y-0214567
X0102528Y-0211583
X0086614Y-0175197
X0086562Y-0169257
X0087167Y-0166377
X0089567Y-016637
X0089567Y-014027
X0087254Y-0139629
X0097409Y-0140111
X009941Y-0141732
X0101409Y-0140111
X0103409Y-0141732
X0105409Y-0140111
X0107409Y-0141732
X0109409Y-0140111
X007185Y-0147638
X0054441Y-01476
X0056441Y-01436
X0052441
X0048441
X0044441
X0040441
X0036441
X0032441
X0028441
X0024441
X0020441
X0016441
X0012441
X0014441Y-01396
X0018441
X0022441
X0026441
X0030441
X0034441
X0038441
X0042441
X0046441
X0050441
X0054441
X0056441Y-01516
X0052441
X0044291Y-0147638
X0034441Y-01476
X0030441
X0026441
X0022441
X0018441
X0014441
X0016441Y-01516
X0020441
X0024441
X0028441
X0032441
X0036441
X0034441Y-01636
X0030441
X0026441
X0022441
X0018441
X0014441
X0010441
X0012441Y-01676
X0016441
X0020441
X0024441
X0028441
X0030512Y-0170276
X0022441Y-01716
X0018441
X0014441
X0010441
X0012441Y-01516
X0010441Y-01396
X0006441
X0044291Y-0167323
X0031496Y-0189961
X0006441Y-02436
X0002441
X-0001559
X0010441Y-02516
Y-02596
X0288189Y-0247638
X0288057Y-0245095
X0287941Y-0241819
X0288189Y-0235827
X0288057Y-0233478
X0288189Y-0231102
Y-022874
X0288583Y-022559
X0269685Y-0136843
X0379134Y-0137795
X0399618Y-0136828
X0405512Y-0136611
X0398568Y-0145083
X0400295Y-0157824
X0401279Y-0162509
X0404528Y-0163386
X040748
Y-0160433
X0406528Y-0157767
X0410528Y-0157923
X0410913Y-0162758
X0420079Y-0162549
X0420669Y-0157923
X043015
Y-0162253
X0439697Y-0162549
X0439961Y-0157923
X0449803
X0449508Y-0162549
X0459319Y-016251
Y-0157922
X0461319Y-014375
X0464328Y-0146397
X0457283Y-0175147
X045085Y-0174127
X0443898Y-0175049
X0437697Y-0175246
X0433858
X0430807Y-0175344
X0427165Y-0175246
X0424213
X0421596Y-0175034
X0417596Y-0175197
X041344Y-017485
X0411043Y-0174974
X0404823Y-0175344
X0402264
X0411811Y-019685
X0416835Y-0196581
X0379921Y-020174
X0377921Y-020374
X0372016Y-0200787
X0366535Y-0202362
X0361417Y-020315
X0361811Y-0207087
X0358661Y-0194488
X0343403Y-0205651
X0338744Y-0205473
X0338844Y-0215273
X0343444Y-0215373
X0343144Y-0225173
X0338444
X0338583Y-0235236
X0343504
X0342744Y-0243747
X0338525Y-0243567
X0338444Y-0254773
X0343144
X0342944Y-0264473
X0338444
X0360236Y-0266186
Y-0268586
Y-027249
Y-0262186
X0360204Y-0252984
X0359252Y-0235236
X0356852
X0354452
X0361652Y-0235205
X0361531Y-0223425
X0359131
X0356578Y-0225247
X0354541Y-0223636
X0323819Y-0227362
Y-0231299
X0325787Y-0229362
Y-0233362
X032385Y-0237205
X0325787Y-0239205
X032385Y-0241173
X0325787Y-0243205
X0314658Y-0244775
X0315097Y-0235081
X0315226Y-0230634
X0314864Y-0227997
X0314503Y-022518
X0326969Y-0197573
X0326966Y-0195171
X0320866Y-027249
X0416106Y-014418
X0418898Y-0144143
X0469291Y-0143848
X0469521Y-0137615
X0494095Y-0137647
X0505905
X0519587Y-0134596
X0538813Y-0144506
X0572047Y-0145669
X0574016
X0575984
X0583071Y-0146063
X0585039
X0587008
X0596063
X0598032
X06
X0580954Y-0207189
X0580935Y-0237412
X0575919Y-0236906
X0586466Y-0247441
X0591978
X0596702
X0603002
X0611094Y-024811
X0555364Y-024941
X0546419Y-0246106
X0544291Y-0233268
X0543276Y-0226591
X0544294Y-0224248
X0544291Y-0215403
X0554519Y-0212889
X0544291Y-0201624
Y-0199655
Y-0197687
Y-0195718
X0531496Y-0203592
X0525591
Y-0213435
X0531496
Y-0223277
X0525591
Y-0233088
X0531496
Y-0242962
X0525591
Y-0253969
X0531496
Y-0262647
X0525591
X0512402Y-0261958
Y-0265108
X0512543Y-0268065
X0512657Y-0270462
X0509842Y-0201624
Y-0199655
Y-0197687
Y-0195718
X046939Y-0175147
X0632432Y-0141142
X0654724Y-0208268
X0656693
X0658661
Y-0211417
X0656693
X0654724
X0650787Y-0229921
X0645669Y-0230315
X0641732
X0638189
X0637795Y-0246457
Y-0248425
Y-0250394
X0640945
Y-0248425
Y-0246457
X0626819Y-0244005
X0632432Y-013248
X0643701Y-0063976
X0651557Y-0064306
X0644685Y-0045276
X0658465Y-0037647
Y-0029773
Y-0021899
X0625
Y-0029773
X0623Y-0037402
X0625Y-004808
X0609252Y-0026575
X0610236Y-0008858
X0615158
X0574016Y-0070472
Y-0072441
Y-007441
X0570866
Y-0072441
Y-0070472
X0570727Y-0105662
X0544813Y-0109806
X0533878Y-0117716
X05344Y-0126969
X0524606Y-0125836
X0524557Y-012874
X0505905Y-0131742
X0492319Y-011497
X0487205Y-0114057
X0483268Y-0114025
X0473425Y-0121899
X0473425Y-0123868
X0473425Y-0125836
X0475295Y-0133612
X0512795Y-0104214
X0518701
X0528543
X0566813Y-0132405
X0593307Y-0131102
X0595276
X0597244
Y-0127953
X0595276
X0593307
X0614321Y-0118307
X0463551Y-0116025
X0456742Y-0116043
X0441929Y-0122883
X0412339Y-0123805
X0375532Y-012361
X037559Y-0127165
X0375984Y-0120079
X0354724Y-0116929
X0352756
X0350787
Y-0113779
X0352756
X0354724
X0330709Y-0120473
Y-0123425
Y-0126378
X0314961Y-0118947
X0309055Y-0123868
X0309016Y-0128659
Y-0113986
X0269685Y-0106151
X0263779
X0267323Y-0122883
X0267286Y-0130697
X025689Y-0124852
Y-0121899
X025Y-0120915
X0244094Y-0109104
X0240945Y-0133465
X0237402
X0234252Y-0133742
X0237008Y-0129576
X0193898Y-0119931
Y-0115009
X0117126Y-0119921
X0119095Y-0122047
X0117126Y-0124047
X0119095Y-0126047
X0117126Y-0128047
X0119095Y-0130047
X0117126Y-0132047
X0109409Y-0112236
X0107346Y-0110236
X0105347Y-0112205
X0103347Y-0110236
X0099347
X0101284Y-0112205
X0097284
X0098425Y-0102362
X0089567
X0086614Y-0110236
X0070866Y-0122047
X0075787Y-013189
X0104528Y-0092175
X0114173Y-0083088
X0129921Y-0079576
X013189Y-0072687
X009941Y-0065797
Y-0057923
Y-0050049
X0065945
Y-0057923
Y-0065797
X0047244Y-0008858
X0040354
X0033465
X0026495Y-0008991
X0026575Y0019685
X0033465Y0019833
X0040354Y0019685
X0047244
X-0023622Y-0060039
Y-0062992
Y-0066929
Y-0070866
Y-0102362
Y-0106299
Y-0110236
Y-0114173
T04
X0598819Y-0228346
X0599065Y-0223031
X0604724Y-0222835
Y-0227953
X0611417
Y-0223228
X0576132Y-0124606
T05
X0470275Y-0308597
X0391535
X0340904Y-027341
Y-019467
X0391545Y-0160477
X0470285
X0528395Y-019468
Y-027342
T06
X0348211Y-0089891
X0357798Y-0089963
T07
X064064Y-003371
Y-0017962
X0082785Y-0053986
Y-0069734
T08
X0539055Y0003937
Y0013937
X0549055
X0559055
X0569055
X0579055
X0589055
Y0003937
X0579055
X0569055
X0559055
X0549055
X0172362Y-0120079
X0162362
X0152362
X0142362
T09
X0246472Y-0327165
X0258472
X0270472
X0282283
X0294094
X0302362Y-0316535
X014252
Y-0236614
Y-0156693
X0302362
T10
X-0008465Y-0316781
X-0008465Y-026363
Y-021048
X-0008465Y-0157332
T11
X0001535Y-0326781
Y-0306781
X-0018464
Y-0326781
X-0018465Y-027363
Y-025363
Y-022048
Y-020048
X-0018464Y-0167332
Y-0147332
X0001535
Y-0167332
X0001535Y-020048
Y-022048
Y-025363
Y-027363
T12
X0624016Y-0194488
Y-0177953
Y-0161417
X0645669
Y-0177953
Y-0194488
T13
X0533015Y-0312764
X0336515
X0336415Y-0155764
X0533015
T14
X0651545Y-0095108
Y0007254
X0413356
Y-0095108
X0310069Y-009495
Y0007412
X007188
Y-009495
T15
X0685039Y-0340551
X0486221Y-0340551
X0685039Y0
T16
X0574291Y-0330039
X0604291
T17
X0674409Y-0194488
Y-0161417
T18
X0Y-0378395
X0Y0
M30
